# S9S_MB_2U (Grand Teton) — schematic netlist excerpt (pin names and nets, part order shuffled) for the footprints in the layout excerpt that follows; sources: Cadence DE-HDL packaged netlist, KiCad conversion of 03242023_DA0F0TMBIJ0_F0T_Motherboard_J_brd_V01_OCP.brd

R929  Q_RES  10K 1% CHIP  pkg 0402LF  page 221 : A = P3V3_AUX ; B = JTAG_BMC_PLD_TMS
C2317  Q_CAP  1UF 25V 10% EMPTY  pkg C0402  page 196 : A = RST_USB_HUB_2_R_N ; B = GND

(kicad_pcb
	(version 20260206)
	(generator "pcbnew")
	(generator_version "10.0")
	(general
		(thickness 1.6)
		(legacy_teardrops no)
	)
	(paper "A4")
	(title_block
		(title "03242023_DA0F0TMBIJ0_F0T_Motherboard_J_brd_V01_OCP.brd")
		(comment 1 "Grand Teton / footprints 2443-2444 of 6105")
	)
	(layers
		(0 "F.Cu" signal "TOP")
		(4 "In1.Cu" signal "GND")
		(6 "In2.Cu" signal "IN1")
		(8 "In3.Cu" signal "GND1")
		(10 "In4.Cu" signal "IN2")
		(12 "In5.Cu" signal "GND2")
		(14 "In6.Cu" signal "IN3")
		(16 "In7.Cu" signal "GND3")
		(18 "In8.Cu" signal "VCC")
		(20 "In9.Cu" signal "VCC1")
		(22 "In10.Cu" signal "GND4")
		(24 "In11.Cu" signal "IN4")
		(26 "In12.Cu" signal "GND5")
		(28 "In13.Cu" signal "IN5")
		(30 "In14.Cu" signal "GND6")
		(32 "In15.Cu" signal "IN6")
		(34 "In16.Cu" signal "GND7")
		(2 "B.Cu" signal "BOTTOM")
		(9 "F.Adhes" user "F.Adhesive")
		(11 "B.Adhes" user "B.Adhesive")
		(13 "F.Paste" user "Package Geometry/Pastemask Top")
		(15 "B.Paste" user "Package Geometry/Pastemask Bottom")
		(5 "F.SilkS" user "Ref Des/Silkscreen Top")
		(7 "B.SilkS" user "Ref Des/Silkscreen Bottom")
		(1 "F.Mask" user "Board Geometry/Soldermask Top")
		(3 "B.Mask" user "Board Geometry/Soldermask Bottom")
		(17 "Dwgs.User" user "User.Drawings")
		(19 "Cmts.User" user "User.Comments")
		(21 "Eco1.User" user "User.Eco1")
		(23 "Eco2.User" user "User.Eco2")
		(25 "Edge.Cuts" user "Board Geometry/Outline")
		(27 "Margin" user)
		(31 "F.CrtYd" user "Package Geometry/Place Bound Top")
		(29 "B.CrtYd" user "Package Geometry/Place Bound Bottom")
		(35 "F.Fab" user "Ref Des/Assembly Top")
		(33 "B.Fab" user "Ref Des/Assembly Bottom")
	)
	(footprint ""
		(layer "F.Cu")
		(at 118.954042 -66.693034 90)
		(property "Reference" "R929"
			(at 0 0 90)
			(layer "F.SilkS")
			(hide yes)
			(effects
				(font
					(size 1.27 1.27)
				)
			)
		)
		(property "Value" ""
			(at 0 0 90)
			(layer "F.Fab")
			(effects
				(font
					(size 1.27 1.27)
				)
			)
		)
		(duplicate_pad_numbers_are_jumpers no)
		(fp_line
			(start 0.7874 -0.4064)
			(end 0.7874 0.4064)
			(stroke
				(width 0.1524)
				(type default)
			)
			(layer "F.SilkS")
		)
		(fp_line
			(start -0.7874 -0.4064)
			(end 0.7874 -0.4064)
			(stroke
				(width 0.1524)
				(type default)
			)
			(layer "F.SilkS")
		)
		(fp_line
			(start 0.7874 0.4064)
			(end -0.7874 0.4064)
			(stroke
				(width 0.1524)
				(type default)
			)
			(layer "F.SilkS")
		)
		(fp_line
			(start -0.7874 0.4064)
			(end -0.7874 -0.4064)
			(stroke
				(width 0.1524)
				(type default)
			)
			(layer "F.SilkS")
		)
		(fp_line
			(start -0.12065 -0.305054)
			(end -0.12065 -0.2794)
			(stroke
				(width 0.1)
				(type default)
			)
			(layer "F.Fab")
		)
		(fp_line
			(start -0.67945 -0.305054)
			(end -0.12065 -0.305054)
			(stroke
				(width 0.1)
				(type default)
			)
			(layer "F.Fab")
		)
		(fp_line
			(start 0.67945 -0.3048)
			(end 0.67945 0.3048)
			(stroke
				(width 0.1)
				(type default)
			)
			(layer "F.Fab")
		)
		(fp_line
			(start 0.12065 -0.3048)
			(end 0.67945 -0.3048)
			(stroke
				(width 0.1)
				(type default)
			)
			(layer "F.Fab")
		)
		(fp_line
			(start 0.12065 -0.2794)
			(end 0.12065 -0.3048)
			(stroke
				(width 0.1)
				(type default)
			)
			(layer "F.Fab")
		)
		(fp_line
			(start -0.12065 -0.2794)
			(end 0.12065 -0.2794)
			(stroke
				(width 0.1)
				(type default)
			)
			(layer "F.Fab")
		)
		(fp_line
			(start 0.120396 0.2794)
			(end -0.12065 0.2794)
			(stroke
				(width 0.1)
				(type default)
			)
			(layer "F.Fab")
		)
		(fp_line
			(start -0.12065 0.2794)
			(end -0.12065 0.3048)
			(stroke
				(width 0.1)
				(type default)
			)
			(layer "F.Fab")
		)
		(fp_line
			(start 0.67945 0.3048)
			(end 0.120396 0.3048)
			(stroke
				(width 0.1)
				(type default)
			)
			(layer "F.Fab")
		)
		(fp_line
			(start 0.120396 0.3048)
			(end 0.120396 0.2794)
			(stroke
				(width 0.1)
				(type default)
			)
			(layer "F.Fab")
		)
		(fp_line
			(start -0.12065 0.3048)
			(end -0.67945 0.3048)
			(stroke
				(width 0.1)
				(type default)
			)
			(layer "F.Fab")
		)
		(fp_line
			(start -0.67945 0.3048)
			(end -0.67945 -0.305054)
			(stroke
				(width 0.1)
				(type default)
			)
			(layer "F.Fab")
		)
		(pad "1" smd circle
			(at -0.40005 0 90)
			(size 0 0)
			(layers "F.Cu" "F.Mask" "F.Paste")
			(net "P3V3_AUX")
		)
		(pad "2" smd circle
			(at 0.40005 0 90)
			(size 0 0)
			(layers "F.Cu" "F.Mask" "F.Paste")
			(net "JTAG_BMC_PLD_TMS")
		)
	)
	(footprint ""
		(layer "F.Cu")
		(at 153.944066 -31.341568 -90)
		(property "Reference" "C2317"
			(at 0 0 270)
			(layer "F.SilkS")
			(hide yes)
			(effects
				(font
					(size 1.27 1.27)
				)
			)
		)
		(property "Value" ""
			(at 0 0 270)
			(layer "F.Fab")
			(effects
				(font
					(size 1.27 1.27)
				)
			)
		)
		(duplicate_pad_numbers_are_jumpers no)
		(fp_line
			(start -0.7874 0.4064)
			(end -0.7874 -0.4064)
			(stroke
				(width 0.1524)
				(type default)
			)
			(layer "F.SilkS")
		)
		(fp_line
			(start 0.7874 0.4064)
			(end -0.7874 0.4064)
			(stroke
				(width 0.1524)
				(type default)
			)
			(layer "F.SilkS")
		)
		(fp_line
			(start -0.7874 -0.4064)
			(end 0.7874 -0.4064)
			(stroke
				(width 0.1524)
				(type default)
			)
			(layer "F.SilkS")
		)
		(fp_line
			(start 0.7874 -0.4064)
			(end 0.7874 0.4064)
			(stroke
				(width 0.1524)
				(type default)
			)
			(layer "F.SilkS")
		)
		(fp_line
			(start -0.67945 0.3048)
			(end -0.67945 -0.305054)
			(stroke
				(width 0.1)
				(type default)
			)
			(layer "F.Fab")
		)
		(fp_line
			(start -0.12065 0.3048)
			(end -0.67945 0.3048)
			(stroke
				(width 0.1)
				(type default)
			)
			(layer "F.Fab")
		)
		(fp_line
			(start 0.120396 0.3048)
			(end 0.120396 0.2794)
			(stroke
				(width 0.1)
				(type default)
			)
			(layer "F.Fab")
		)
		(fp_line
			(start 0.67945 0.3048)
			(end 0.120396 0.3048)
			(stroke
				(width 0.1)
				(type default)
			)
			(layer "F.Fab")
		)
		(fp_line
			(start -0.12065 0.2794)
			(end -0.12065 0.3048)
			(stroke
				(width 0.1)
				(type default)
			)
			(layer "F.Fab")
		)
		(fp_line
			(start 0.120396 0.2794)
			(end -0.12065 0.2794)
			(stroke
				(width 0.1)
				(type default)
			)
			(layer "F.Fab")
		)
		(fp_line
			(start -0.12065 -0.2794)
			(end 0.12065 -0.2794)
			(stroke
				(width 0.1)
				(type default)
			)
			(layer "F.Fab")
		)
		(fp_line
			(start 0.12065 -0.2794)
			(end 0.12065 -0.3048)
			(stroke
				(width 0.1)
				(type default)
			)
			(layer "F.Fab")
		)
		(fp_line
			(start 0.12065 -0.3048)
			(end 0.67945 -0.3048)
			(stroke
				(width 0.1)
				(type default)
			)
			(layer "F.Fab")
		)
		(fp_line
			(start 0.67945 -0.3048)
			(end 0.67945 0.3048)
			(stroke
				(width 0.1)
				(type default)
			)
			(layer "F.Fab")
		)
		(fp_line
			(start -0.67945 -0.305054)
			(end -0.12065 -0.305054)
			(stroke
				(width 0.1)
				(type default)
			)
			(layer "F.Fab")
		)
		(fp_line
			(start -0.12065 -0.305054)
			(end -0.12065 -0.2794)
			(stroke
				(width 0.1)
				(type default)
			)
			(layer "F.Fab")
		)
		(pad "1" smd circle
			(at -0.40005 0 270)
			(size 0 0)
			(layers "F.Cu" "F.Mask" "F.Paste")
			(net "RST_USB_HUB_2_R_N")
		)
		(pad "2" smd circle
			(at 0.40005 0 270)
			(size 0 0)
			(layers "F.Cu" "F.Mask" "F.Paste")
			(net "GND")
		)
	)
)
